# S9S_MB_2U (Grand Teton) — schematic netlist excerpt (pin names and nets, part order shuffled) for the footprints in the layout excerpt that follows; sources: Cadence DE-HDL packaged netlist, KiCad conversion of 03242023_DA0F0TMBIJ0_F0T_Motherboard_J_brd_V01_OCP.brd

C12  Q_CAP  10UF 16V 10% X6S  pkg C0805  page 85 : A = P12V_S3_AUX_CPU0_NVDIMM ; B = GND
PC814  Q_CAP  1UF 16V 10% X6S  pkg C0402  page 296 : A = PVCCD_HV_CPU1_ISENSE_N ; B = PVCCD_HV_CPU1_ISENSE_P
PC1990  Q_CAPP  330UF 2.5V +10/-35% EMPTY  pkg SMLF  page 285 : A = PVCCIN_CPU1 ; B = GND

(kicad_pcb
	(version 20260206)
	(generator "pcbnew")
	(generator_version "10.0")
	(general
		(thickness 1.6)
		(legacy_teardrops no)
	)
	(paper "A4")
	(title_block
		(title "03242023_DA0F0TMBIJ0_F0T_Motherboard_J_brd_V01_OCP.brd")
		(comment 1 "Grand Teton / footprints 5458-5460 of 6105")
	)
	(layers
		(0 "F.Cu" signal "TOP")
		(4 "In1.Cu" signal "GND")
		(6 "In2.Cu" signal "IN1")
		(8 "In3.Cu" signal "GND1")
		(10 "In4.Cu" signal "IN2")
		(12 "In5.Cu" signal "GND2")
		(14 "In6.Cu" signal "IN3")
		(16 "In7.Cu" signal "GND3")
		(18 "In8.Cu" signal "VCC")
		(20 "In9.Cu" signal "VCC1")
		(22 "In10.Cu" signal "GND4")
		(24 "In11.Cu" signal "IN4")
		(26 "In12.Cu" signal "GND5")
		(28 "In13.Cu" signal "IN5")
		(30 "In14.Cu" signal "GND6")
		(32 "In15.Cu" signal "IN6")
		(34 "In16.Cu" signal "GND7")
		(2 "B.Cu" signal "BOTTOM")
		(9 "F.Adhes" user "F.Adhesive")
		(11 "B.Adhes" user "B.Adhesive")
		(13 "F.Paste" user "Package Geometry/Pastemask Top")
		(15 "B.Paste" user "Package Geometry/Pastemask Bottom")
		(5 "F.SilkS" user "Ref Des/Silkscreen Top")
		(7 "B.SilkS" user "Ref Des/Silkscreen Bottom")
		(1 "F.Mask" user "Board Geometry/Soldermask Top")
		(3 "B.Mask" user "Board Geometry/Soldermask Bottom")
		(17 "Dwgs.User" user "User.Drawings")
		(19 "Cmts.User" user "User.Comments")
		(21 "Eco1.User" user "User.Eco1")
		(23 "Eco2.User" user "User.Eco2")
		(25 "Edge.Cuts" user "Board Geometry/Outline")
		(27 "Margin" user)
		(31 "F.CrtYd" user "Package Geometry/Place Bound Top")
		(29 "B.CrtYd" user "Package Geometry/Place Bound Bottom")
		(35 "F.Fab" user "Ref Des/Assembly Top")
		(33 "B.Fab" user "Ref Des/Assembly Bottom")
	)
	(footprint ""
		(layer "B.Cu")
		(at 113.677954 -326.99706 -90)
		(property "Reference" "PC1990"
			(at 0 0 90)
			(layer "B.SilkS")
			(hide yes)
			(effects
				(font
					(size 1.27 1.27)
				)
				(justify mirror)
			)
		)
		(property "Value" ""
			(at 0 0 90)
			(layer "B.Fab")
			(effects
				(font
					(size 1.27 1.27)
				)
				(justify mirror)
			)
		)
		(duplicate_pad_numbers_are_jumpers no)
		(fp_line
			(start -4.533392 2.249932)
			(end 4.533392 2.249932)
			(stroke
				(width 0.1524)
				(type default)
			)
			(layer "B.SilkS")
		)
		(fp_line
			(start 4.533392 2.249932)
			(end 4.533392 -2.249932)
			(stroke
				(width 0.1524)
				(type default)
			)
			(layer "B.SilkS")
		)
		(fp_line
			(start -4.533392 -2.249932)
			(end -4.533392 2.249932)
			(stroke
				(width 0.1524)
				(type default)
			)
			(layer "B.SilkS")
		)
		(fp_line
			(start 4.533392 -2.249932)
			(end -4.533392 -2.249932)
			(stroke
				(width 0.1524)
				(type default)
			)
			(layer "B.SilkS")
		)
		(fp_rect
			(start 5.39242 2.326132)
			(end 4.533392 -2.326132)
			(stroke
				(width 0)
				(type default)
			)
			(fill yes)
			(layer "B.SilkS")
		)
		(fp_line
			(start -3.750056 2.249932)
			(end 3.750056 2.249932)
			(stroke
				(width 0.1)
				(type default)
			)
			(layer "B.Fab")
		)
		(fp_line
			(start 3.750056 2.249932)
			(end 3.750056 -2.249932)
			(stroke
				(width 0.1)
				(type default)
			)
			(layer "B.Fab")
		)
		(fp_line
			(start -3.750056 -2.249932)
			(end -3.750056 2.249932)
			(stroke
				(width 0.1)
				(type default)
			)
			(layer "B.Fab")
		)
		(fp_line
			(start 3.750056 -2.249932)
			(end -3.750056 -2.249932)
			(stroke
				(width 0.1)
				(type default)
			)
			(layer "B.Fab")
		)
		(fp_text user "-"
			(at -4.719828 1.309624 270)
			(unlocked yes)
			(layer "B.SilkS")
			(effects
				(font
					(size 1.905 1.4224)
					(thickness 0.1524)
				)
				(justify left mirror)
			)
		)
		(fp_text user "+"
			(at 6.322314 0.786384 180)
			(unlocked yes)
			(layer "B.SilkS")
			(effects
				(font
					(size 1.905 1.4224)
					(thickness 0.1524)
				)
				(justify left mirror)
			)
		)
		(fp_text user "+"
			(at 6.322314 0.786384 180)
			(unlocked yes)
			(layer "B.Fab")
			(effects
				(font
					(size 1.905 1.4224)
					(thickness 0.1524)
				)
				(justify left mirror)
			)
		)
		(fp_text user "-"
			(at -4.8514 -0.14605 270)
			(unlocked yes)
			(layer "B.Fab")
			(effects
				(font
					(size 1.905 1.4224)
					(thickness 0.1524)
				)
				(justify left mirror)
			)
		)
		(pad "1" smd rect
			(at 3.199892 0 90)
			(size 2.413 2.8194)
			(layers "B.Cu" "B.Mask" "B.Paste")
			(net "PVCCIN_CPU1")
		)
		(pad "2" smd rect
			(at -3.199892 0 90)
			(size 2.413 2.8194)
			(layers "B.Cu" "B.Mask" "B.Paste")
			(net "GND")
		)
	)
	(footprint ""
		(layer "B.Cu")
		(at 293.812214 -321.549776 -90)
		(property "Reference" "C12"
			(at 0 0 90)
			(layer "B.SilkS")
			(hide yes)
			(effects
				(font
					(size 1.27 1.27)
				)
				(justify mirror)
			)
		)
		(property "Value" ""
			(at 0 0 90)
			(layer "B.Fab")
			(effects
				(font
					(size 1.27 1.27)
				)
				(justify mirror)
			)
		)
		(duplicate_pad_numbers_are_jumpers no)
		(fp_line
			(start -1.524 0.762)
			(end 1.524 0.762)
			(stroke
				(width 0.1524)
				(type default)
			)
			(layer "B.SilkS")
		)
		(fp_line
			(start 1.524 0.762)
			(end 1.524 -0.762)
			(stroke
				(width 0.1524)
				(type default)
			)
			(layer "B.SilkS")
		)
		(fp_line
			(start -1.524 -0.762)
			(end -1.524 0.762)
			(stroke
				(width 0.1524)
				(type default)
			)
			(layer "B.SilkS")
		)
		(fp_line
			(start 1.524 -0.762)
			(end -1.524 -0.762)
			(stroke
				(width 0.1524)
				(type default)
			)
			(layer "B.SilkS")
		)
		(fp_line
			(start -1.1049 0.724916)
			(end -1.1049 -0.724916)
			(stroke
				(width 0.1)
				(type default)
			)
			(layer "B.Fab")
		)
		(fp_line
			(start 1.1049 0.724916)
			(end -1.1049 0.724916)
			(stroke
				(width 0.1)
				(type default)
			)
			(layer "B.Fab")
		)
		(fp_line
			(start -1.1049 -0.724916)
			(end 1.1049 -0.724916)
			(stroke
				(width 0.1)
				(type default)
			)
			(layer "B.Fab")
		)
		(fp_line
			(start 1.1049 -0.724916)
			(end 1.1049 0.724916)
			(stroke
				(width 0.1)
				(type default)
			)
			(layer "B.Fab")
		)
		(pad "1" smd rect
			(at 0.889 0 270)
			(size 1.016 1.27)
			(layers "B.Cu" "B.Mask" "B.Paste")
			(net "P12V_S3_AUX_CPU0_NVDIMM")
		)
		(pad "2" smd rect
			(at -0.889 0 270)
			(size 1.016 1.27)
			(layers "B.Cu" "B.Mask" "B.Paste")
			(net "GND")
		)
	)
	(footprint ""
		(layer "B.Cu")
		(at 31.94304 -166.25316 90)
		(property "Reference" "PC814"
			(at 0 0 90)
			(layer "B.SilkS")
			(hide yes)
			(effects
				(font
					(size 1.27 1.27)
				)
				(justify mirror)
			)
		)
		(property "Value" ""
			(at 0 0 90)
			(layer "B.Fab")
			(effects
				(font
					(size 1.27 1.27)
				)
				(justify mirror)
			)
		)
		(duplicate_pad_numbers_are_jumpers no)
		(fp_line
			(start 0.7874 -0.4064)
			(end -0.7874 -0.4064)
			(stroke
				(width 0.1524)
				(type default)
			)
			(layer "B.SilkS")
		)
		(fp_line
			(start -0.7874 -0.4064)
			(end -0.7874 0.4064)
			(stroke
				(width 0.1524)
				(type default)
			)
			(layer "B.SilkS")
		)
		(fp_line
			(start 0.7874 0.4064)
			(end 0.7874 -0.4064)
			(stroke
				(width 0.1524)
				(type default)
			)
			(layer "B.SilkS")
		)
		(fp_line
			(start -0.7874 0.4064)
			(end 0.7874 0.4064)
			(stroke
				(width 0.1524)
				(type default)
			)
			(layer "B.SilkS")
		)
		(fp_line
			(start 0.67945 -0.305054)
			(end 0.12065 -0.305054)
			(stroke
				(width 0.1)
				(type default)
			)
			(layer "B.Fab")
		)
		(fp_line
			(start 0.12065 -0.305054)
			(end 0.12065 -0.2794)
			(stroke
				(width 0.1)
				(type default)
			)
			(layer "B.Fab")
		)
		(fp_line
			(start -0.12065 -0.3048)
			(end -0.67945 -0.3048)
			(stroke
				(width 0.1)
				(type default)
			)
			(layer "B.Fab")
		)
		(fp_line
			(start -0.67945 -0.3048)
			(end -0.67945 0.3048)
			(stroke
				(width 0.1)
				(type default)
			)
			(layer "B.Fab")
		)
		(fp_line
			(start 0.12065 -0.2794)
			(end -0.12065 -0.2794)
			(stroke
				(width 0.1)
				(type default)
			)
			(layer "B.Fab")
		)
		(fp_line
			(start -0.12065 -0.2794)
			(end -0.12065 -0.3048)
			(stroke
				(width 0.1)
				(type default)
			)
			(layer "B.Fab")
		)
		(fp_line
			(start 0.12065 0.2794)
			(end 0.12065 0.3048)
			(stroke
				(width 0.1)
				(type default)
			)
			(layer "B.Fab")
		)
		(fp_line
			(start -0.120396 0.2794)
			(end 0.12065 0.2794)
			(stroke
				(width 0.1)
				(type default)
			)
			(layer "B.Fab")
		)
		(fp_line
			(start 0.67945 0.3048)
			(end 0.67945 -0.305054)
			(stroke
				(width 0.1)
				(type default)
			)
			(layer "B.Fab")
		)
		(fp_line
			(start 0.12065 0.3048)
			(end 0.67945 0.3048)
			(stroke
				(width 0.1)
				(type default)
			)
			(layer "B.Fab")
		)
		(fp_line
			(start -0.120396 0.3048)
			(end -0.120396 0.2794)
			(stroke
				(width 0.1)
				(type default)
			)
			(layer "B.Fab")
		)
		(fp_line
			(start -0.67945 0.3048)
			(end -0.120396 0.3048)
			(stroke
				(width 0.1)
				(type default)
			)
			(layer "B.Fab")
		)
		(pad "1" smd circle
			(at 0.40005 0 270)
			(size 0 0)
			(layers "B.Cu" "B.Mask" "B.Paste")
			(net "PVCCD_HV_CPU1_ISENSE_N")
		)
		(pad "2" smd circle
			(at -0.40005 0 270)
			(size 0 0)
			(layers "B.Cu" "B.Mask" "B.Paste")
			(net "PVCCD_HV_CPU1_ISENSE_P")
		)
	)
)
